(kicad_pcb
	(version 20241229)
	(generator "pcbnew")
	(generator_version "9.0")
	(general
		(thickness 1.711)
		(legacy_teardrops no)
	)
	(paper "A4")
	(title_block
		(title "Antmicro Baseboard for Jetson AGX Thor")
		(date "2026-02-18")
		(rev "1.1.0")
		(company "Antmicro Ltd")
		(comment 1 "www.antmicro.com")
		(comment 9 "footprints 772-775 of 1170")
	)
	(layers
		(0 "F.Cu" signal)
		(4 "In1.Cu" signal)
		(6 "In2.Cu" signal)
		(8 "In3.Cu" signal)
		(10 "In4.Cu" jumper)
		(12 "In5.Cu" signal)
		(14 "In6.Cu" signal)
		(16 "In7.Cu" signal)
		(18 "In8.Cu" signal)
		(2 "B.Cu" signal)
		(9 "F.Adhes" user "F.Adhesive")
		(11 "B.Adhes" user "B.Adhesive")
		(13 "F.Paste" user)
		(15 "B.Paste" user)
		(5 "F.SilkS" user "F.Silkscreen")
		(7 "B.SilkS" user "B.Silkscreen")
		(1 "F.Mask" user)
		(3 "B.Mask" user)
		(17 "Dwgs.User" user "User.Drawings")
		(19 "Cmts.User" user "User.Comments")
		(21 "Eco1.User" user "User.Eco1")
		(23 "Eco2.User" user "User.Eco2")
		(25 "Edge.Cuts" user)
		(27 "Margin" user)
		(31 "F.CrtYd" user "F.Courtyard")
		(29 "B.CrtYd" user "B.Courtyard")
		(35 "F.Fab" user)
		(33 "B.Fab" user)
	)
	(footprint "antmicro-footprints:C_0402_1005Metric"
		(layer "B.Cu")
		(at 97.75 54.5 180)
		(descr "Capacitor SMD 0402")
		(tags "capacitor SMD 0402")
		(property "Reference" "C226"
			(at -4 -0.5 0)
			(layer "B.SilkS")
			(effects
				(font
					(size 0.7 0.7)
					(thickness 0.15)
				)
				(justify left bottom mirror)
			)
		)
		(property "Value" "C_1u_25V_0402"
			(at -1.022927 -2.155213 0)
			(layer "B.Fab")
			(effects
				(font
					(size 0.7 0.7)
					(thickness 0.15)
				)
				(justify left bottom mirror)
			)
		)
		(property "Datasheet" "https://www.murata.com/products/productdetail?partno=GRM155R61E105KE11%23"
			(at 0 0 0)
			(layer "B.Fab")
			(hide yes)
			(effects
				(font
					(size 1.27 1.27)
					(thickness 0.15)
				)
				(justify mirror)
			)
		)
		(property "Description" "SMD Multilayer Ceramic Capacitor, 1 µF, 25 V, 0402 [1005 Metric], ± 10%, X5R, GRM Series"
			(at 0 0 0)
			(layer "B.Fab")
			(hide yes)
			(effects
				(font
					(size 1.27 1.27)
					(thickness 0.15)
				)
				(justify mirror)
			)
		)
		(property "MPN" "GRM155R61E105KE11J"
			(at 0 0 0)
			(unlocked yes)
			(layer "B.Fab")
			(hide yes)
			(effects
				(font
					(size 1 1)
					(thickness 0.15)
				)
				(justify mirror)
			)
		)
		(property "Manufacturer" "Murata"
			(at 0 0 0)
			(unlocked yes)
			(layer "B.Fab")
			(hide yes)
			(effects
				(font
					(size 1 1)
					(thickness 0.15)
				)
				(justify mirror)
			)
		)
		(property "License" "Apache-2.0"
			(at 0 0 0)
			(unlocked yes)
			(layer "B.Fab")
			(hide yes)
			(effects
				(font
					(size 1 1)
					(thickness 0.15)
				)
				(justify mirror)
			)
		)
		(property "Author" "Antmicro"
			(at 0 0 0)
			(unlocked yes)
			(layer "B.Fab")
			(hide yes)
			(effects
				(font
					(size 1 1)
					(thickness 0.15)
				)
				(justify mirror)
			)
		)
		(property "Val" "1u"
			(at 0 0 0)
			(unlocked yes)
			(layer "B.Fab")
			(hide yes)
			(effects
				(font
					(size 1 1)
					(thickness 0.15)
				)
				(justify mirror)
			)
		)
		(property "Voltage" "25V"
			(at 0 0 0)
			(unlocked yes)
			(layer "B.Fab")
			(hide yes)
			(effects
				(font
					(size 1 1)
					(thickness 0.15)
				)
				(justify mirror)
			)
		)
		(property "Dielectric" "X5R"
			(at 0 0 0)
			(unlocked yes)
			(layer "B.Fab")
			(hide yes)
			(effects
				(font
					(size 1 1)
					(thickness 0.15)
				)
				(justify mirror)
			)
		)
		(sheetname "/SoM_Power/")
		(sheetfile "som_power.kicad_sch")
		(attr smd)
		(fp_poly
			(pts
				(xy -0.925 0.47) (xy -0.925 -0.47) (xy 0.925 -0.47) (xy 0.925 0.47)
			)
			(stroke
				(width 0.05)
				(type default)
			)
			(fill no)
			(layer "B.CrtYd")
		)
		(fp_line
			(start 0.504 0.25)
			(end 0.504 -0.248)
			(stroke
				(width 0.15)
				(type solid)
			)
			(layer "B.Fab")
		)
		(fp_line
			(start 0.504 -0.248)
			(end -0.494 -0.248)
			(stroke
				(width 0.15)
				(type solid)
			)
			(layer "B.Fab")
		)
		(fp_line
			(start -0.494 0.25)
			(end 0.504 0.25)
			(stroke
				(width 0.15)
				(type solid)
			)
			(layer "B.Fab")
		)
		(fp_line
			(start -0.494 -0.248)
			(end -0.494 0.25)
			(stroke
				(width 0.15)
				(type solid)
			)
			(layer "B.Fab")
		)
		(fp_text user "Author: Antmicro"
			(at -0.939 -3.399 0)
			(layer "B.Fab")
			(effects
				(font
					(size 0.7 0.7)
					(thickness 0.15)
				)
				(justify left bottom mirror)
			)
		)
		(fp_text user "License: Apache-2.0"
			(at -0.939 -5.799 0)
			(layer "B.Fab")
			(effects
				(font
					(size 0.7 0.7)
					(thickness 0.15)
				)
				(justify left bottom mirror)
			)
		)
		(fp_text user "${REFERENCE}"
			(at -0.939 -4.599 0)
			(layer "B.Fab")
			(effects
				(font
					(size 0.7 0.7)
					(thickness 0.15)
				)
				(justify left bottom mirror)
			)
		)
		(pad "1" smd roundrect
			(at -0.48 0 180)
			(size 0.59 0.64)
			(layers "B.Cu" "B.Mask" "B.Paste")
			(roundrect_rratio 0.25)
			(net 1 "GND")
			(pintype "passive")
		)
		(pad "2" smd roundrect
			(at 0.48 0 180)
			(size 0.59 0.64)
			(layers "B.Cu" "B.Mask" "B.Paste")
			(roundrect_rratio 0.25)
			(net 521 "Net-(U72-CT)")
			(pintype "passive")
		)
	)
	(footprint "antmicro-footprints:LED_0603_1608Metric_G"
		(layer "B.Cu")
		(at 235.55 61.975)
		(descr "LED SMD 0603 Green")
		(tags "LED SMD 0603 Green")
		(property "Reference" "D53"
			(at -6.25 0.025 0)
			(layer "B.SilkS")
			(effects
				(font
					(size 0.7 0.7)
					(thickness 0.15)
				)
				(justify right top mirror)
			)
		)
		(property "Value" "LED_G_0603_LTST-C190GKT"
			(at -0.001 -1.599 0)
			(layer "B.Fab")
			(effects
				(font
					(size 0.7 0.7)
					(thickness 0.15)
				)
				(justify right top mirror)
			)
		)
		(property "Datasheet" "https://media.digikey.com/pdf/Data%20Sheets/Lite-On%20PDFs/LTST-C190GKT.pdf"
			(at 0 0 0)
			(layer "B.Fab")
			(hide yes)
			(effects
				(font
					(size 1.27 1.27)
					(thickness 0.15)
				)
				(justify mirror)
			)
		)
		(property "Description" "LED, Green, SMD, 0603, 20 mA, 2.1 V, 569 nm"
			(at 0 0 0)
			(layer "B.Fab")
			(hide yes)
			(effects
				(font
					(size 1.27 1.27)
					(thickness 0.15)
				)
				(justify mirror)
			)
		)
		(property "MPN" "LTST-C190GKT"
			(at 0 0 180)
			(unlocked yes)
			(layer "B.Fab")
			(hide yes)
			(effects
				(font
					(size 1 1)
					(thickness 0.15)
				)
				(justify mirror)
			)
		)
		(property "Manufacturer" "Lite-On"
			(at 0 0 180)
			(unlocked yes)
			(layer "B.Fab")
			(hide yes)
			(effects
				(font
					(size 1 1)
					(thickness 0.15)
				)
				(justify mirror)
			)
		)
		(property "Author" "Antmicro"
			(at 0 0 180)
			(unlocked yes)
			(layer "B.Fab")
			(hide yes)
			(effects
				(font
					(size 1 1)
					(thickness 0.15)
				)
				(justify mirror)
			)
		)
		(property "License" "Apache-2.0"
			(at 0 0 180)
			(unlocked yes)
			(layer "B.Fab")
			(hide yes)
			(effects
				(font
					(size 1 1)
					(thickness 0.15)
				)
				(justify mirror)
			)
		)
		(property "Color" "Green"
			(at 0 0 180)
			(unlocked yes)
			(layer "B.Fab")
			(hide yes)
			(effects
				(font
					(size 1 1)
					(thickness 0.15)
				)
				(justify mirror)
			)
		)
		(sheetname "/Power/")
		(sheetfile "power.kicad_sch")
		(attr smd)
		(fp_line
			(start -1.18 0.319)
			(end -1.18 -0.321)
			(stroke
				(width 0.15)
				(type solid)
			)
			(layer "B.SilkS")
		)
		(fp_line
			(start -0.094672 -0.201008)
			(end -0.094672 0.198992)
			(stroke
				(width 0.1)
				(type solid)
			)
			(layer "B.SilkS")
		)
		(fp_line
			(start -0.094672 -0.001008)
			(end -0.24 -0.001008)
			(stroke
				(width 0.1)
				(type solid)
			)
			(layer "B.SilkS")
		)
		(fp_line
			(start -0.094672 -0.001008)
			(end 0.105329 0.198992)
			(stroke
				(width 0.1)
				(type solid)
			)
			(layer "B.SilkS")
		)
		(fp_line
			(start 0.105328 -0.201008)
			(end -0.094672 -0.001008)
			(stroke
				(width 0.1)
				(type solid)
			)
			(layer "B.SilkS")
		)
		(fp_line
			(start 0.105328 -0.201008)
			(end 0.105329 0.198992)
			(stroke
				(width 0.1)
				(type solid)
			)
			(layer "B.SilkS")
		)
		(fp_line
			(start 0.105328 -0.001008)
			(end 0.240001 -0.001)
			(stroke
				(width 0.1)
				(type solid)
			)
			(layer "B.SilkS")
		)
		(fp_line
			(start 0.22 -0.35)
			(end -0.22 -0.35)
			(stroke
				(width 0.15)
				(type solid)
			)
			(layer "B.SilkS")
		)
		(fp_line
			(start 0.22 0.35)
			(end -0.22 0.35)
			(stroke
				(width 0.15)
				(type solid)
			)
			(layer "B.SilkS")
		)
		(fp_poly
			(pts
				(xy 1.25 -0.65) (xy -1.25 -0.65) (xy -1.25 0.65) (xy 1.25 0.65)
			)
			(stroke
				(width 0.05)
				(type solid)
			)
			(fill no)
			(layer "B.CrtYd")
		)
		(fp_line
			(start -0.199 -0.2)
			(end -0.199 -0.1)
			(stroke
				(width 0.15)
				(type solid)
			)
			(layer "B.Fab")
		)
		(fp_line
			(start -0.199 0)
			(end -0.597 0)
			(stroke
				(width 0.15)
				(type solid)
			)
			(layer "B.Fab")
		)
		(fp_line
			(start -0.199 0.202)
			(end -0.199 -0.1)
			(stroke
				(width 0.15)
				(type solid)
			)
			(layer "B.Fab")
		)
		(fp_line
			(start -0.101 0)
			(end 0.201 -0.2)
			(stroke
				(width 0.15)
				(type solid)
			)
			(layer "B.Fab")
		)
		(fp_line
			(start 0.200999 0)
			(end 0.201 0.202)
			(stroke
				(width 0.15)
				(type solid)
			)
			(layer "B.Fab")
		)
		(fp_line
			(start 0.201 -0.2)
			(end 0.200999 0)
			(stroke
				(width 0.15)
				(type solid)
			)
			(layer "B.Fab")
		)
		(fp_line
			(start 0.201 0.202)
			(end -0.101 0)
			(stroke
				(width 0.15)
				(type solid)
			)
			(layer "B.Fab")
		)
		(fp_line
			(start 0.599 0)
			(end 0.200999 0)
			(stroke
				(width 0.15)
				(type solid)
			)
			(layer "B.Fab")
		)
		(fp_poly
			(pts
				(xy 0.848 -0.4) (xy -0.85 -0.4) (xy -0.85 0.402) (xy 0.848 0.401999)
			)
			(stroke
				(width 0.15)
				(type solid)
			)
			(fill no)
			(layer "B.Fab")
		)
		(fp_text user "${REFERENCE}"
			(at -1.4224 -5.999 0)
			(layer "B.Fab")
			(effects
				(font
					(size 0.7 0.7)
					(thickness 0.15)
				)
				(justify right top mirror)
			)
		)
		(fp_text user "License: Apache-2.0"
			(at -1.4224 -3.599 0)
			(layer "B.Fab")
			(effects
				(font
					(size 0.7 0.7)
					(thickness 0.15)
				)
				(justify right top mirror)
			)
		)
		(fp_text user "Author: Antmicro"
			(at -1.4224 -4.799 0)
			(layer "B.Fab")
			(effects
				(font
					(size 0.7 0.7)
					(thickness 0.15)
				)
				(justify right top mirror)
			)
		)
		(pad "1" smd roundrect
			(at -0.7 0 180)
			(size 0.8 1)
			(layers "B.Cu" "B.Mask" "B.Paste")
			(roundrect_rratio 0.2)
			(net 1 "GND")
			(pinfunction "C")
			(pintype "passive")
		)
		(pad "2" smd roundrect
			(at 0.7 0 180)
			(size 0.8 1)
			(layers "B.Cu" "B.Mask" "B.Paste")
			(roundrect_rratio 0.2)
			(net 1395 "Net-(D53-A)")
			(pinfunction "A")
			(pintype "passive")
		)
	)
	(footprint "antmicro-footprints:R_0402_1005Metric"
		(layer "B.Cu")
		(at 161.92 62.8 90)
		(descr "Resistor SMD 0402")
		(tags "resistor SMD 0402")
		(property "Reference" "R126"
			(at -7.037 -8.42 90)
			(layer "B.SilkS")
			(effects
				(font
					(size 0.7 0.7)
					(thickness 0.15)
				)
				(justify right top mirror)
			)
		)
		(property "Value" "R_10k_0402"
			(at -1.011843 -1.772047 90)
			(layer "B.Fab")
			(effects
				(font
					(size 0.7 0.7)
					(thickness 0.15)
				)
				(justify right top mirror)
			)
		)
		(property "Datasheet" "https://www.bourns.com/docs/product-datasheets/cr.pdf"
			(at 0 0 90)
			(layer "B.Fab")
			(hide yes)
			(effects
				(font
					(size 1.27 1.27)
					(thickness 0.15)
				)
				(justify mirror)
			)
		)
		(property "Description" "SMD Chip Resistor, 10 kohm, ± 1%, 62.5 mW, 0402 [1005 Metric], Thick Film, General Purpose"
			(at 0 0 90)
			(layer "B.Fab")
			(hide yes)
			(effects
				(font
					(size 1.27 1.27)
					(thickness 0.15)
				)
				(justify mirror)
			)
		)
		(property "MPN" "CR0402-FX-1002GLF"
			(at 0 0 270)
			(unlocked yes)
			(layer "B.Fab")
			(hide yes)
			(effects
				(font
					(size 1 1)
					(thickness 0.15)
				)
				(justify mirror)
			)
		)
		(property "Manufacturer" "Bourns"
			(at 0 0 270)
			(unlocked yes)
			(layer "B.Fab")
			(hide yes)
			(effects
				(font
					(size 1 1)
					(thickness 0.15)
				)
				(justify mirror)
			)
		)
		(property "License" "Apache-2.0"
			(at 0 0 270)
			(unlocked yes)
			(layer "B.Fab")
			(hide yes)
			(effects
				(font
					(size 1 1)
					(thickness 0.15)
				)
				(justify mirror)
			)
		)
		(property "Author" "Antmicro"
			(at 0 0 270)
			(unlocked yes)
			(layer "B.Fab")
			(hide yes)
			(effects
				(font
					(size 1 1)
					(thickness 0.15)
				)
				(justify mirror)
			)
		)
		(property "Val" "10k"
			(at 0 0 270)
			(unlocked yes)
			(layer "B.Fab")
			(hide yes)
			(effects
				(font
					(size 1 1)
					(thickness 0.15)
				)
				(justify mirror)
			)
		)
		(property "Tolerance" "1%"
			(at 0 0 270)
			(unlocked yes)
			(layer "B.Fab")
			(hide yes)
			(effects
				(font
					(size 1 1)
					(thickness 0.15)
				)
				(justify mirror)
			)
		)
		(sheetname "/SoM_IO2/")
		(sheetfile "som_io2.kicad_sch")
		(attr smd exclude_from_pos_files exclude_from_bom dnp)
		(fp_rect
			(start -0.925 0.47)
			(end 0.925 -0.47)
			(stroke
				(width 0.05)
				(type default)
			)
			(fill no)
			(layer "B.CrtYd")
		)
		(fp_rect
			(start -0.5 0.25)
			(end 0.5 -0.25)
			(stroke
				(width 0.15)
				(type solid)
			)
			(fill no)
			(layer "B.Fab")
		)
		(fp_text user "License: Apache-2.0"
			(at -0.95 -5.169 90)
			(layer "B.Fab")
			(effects
				(font
					(size 0.7 0.7)
					(thickness 0.15)
				)
				(justify right top mirror)
			)
		)
		(fp_text user "Author: Antmicro"
			(at -0.95 -4.169 90)
			(layer "B.Fab")
			(effects
				(font
					(size 0.7 0.7)
					(thickness 0.15)
				)
				(justify right top mirror)
			)
		)
		(fp_text user "${REFERENCE}"
			(at -0.95 -3.168 90)
			(layer "B.Fab")
			(effects
				(font
					(size 0.7 0.7)
					(thickness 0.15)
				)
				(justify right top mirror)
			)
		)
		(pad "1" smd roundrect
			(at -0.48 0 90)
			(size 0.59 0.64)
			(layers "B.Cu" "B.Mask" "B.Paste")
			(roundrect_rratio 0.25)
			(net 1299 "Net-(Q28-G)")
			(pintype "passive")
		)
		(pad "2" smd roundrect
			(at 0.48 0 90)
			(size 0.59 0.64)
			(layers "B.Cu" "B.Mask" "B.Paste")
			(roundrect_rratio 0.25)
			(net 11 "+1V8")
			(pintype "passive")
		)
	)
	(footprint "antmicro-footprints:TSOT23-6"
		(layer "B.Cu")
		(at 135.6 62.08 -90)
		(property "Reference" "U53"
			(at -0.21 -2.72 90)
			(layer "B.SilkS")
			(effects
				(font
					(size 0.7 0.7)
					(thickness 0.15)
				)
				(justify left bottom mirror)
			)
		)
		(property "Value" "AP22615A_TSOT26"
			(at 0 -2.6 90)
			(layer "B.Fab")
			(effects
				(font
					(size 0.7 0.7)
					(thickness 0.15)
				)
				(justify left bottom mirror)
			)
		)
		(property "Datasheet" "https://www.mouser.com/datasheet/2/115/DIOD_S_A0008958405_1-2543193.pdf"
			(at 0 0 90)
			(layer "B.Fab")
			(hide yes)
			(effects
				(font
					(size 1.27 1.27)
					(thickness 0.15)
				)
				(justify mirror)
			)
		)
		(property "Description" "Power Load Distribution Switch, High Side, Active High, 1 Output, 5.5 V, 3.6 A, 0.04 ohm, TSOT-26-6"
			(at 0 0 90)
			(layer "B.Fab")
			(hide yes)
			(effects
				(font
					(size 1.27 1.27)
					(thickness 0.15)
				)
				(justify mirror)
			)
		)
		(property "MPN" "AP22615AWU-7"
			(at 0 0 270)
			(unlocked yes)
			(layer "B.Fab")
			(hide yes)
			(effects
				(font
					(size 1 1)
					(thickness 0.15)
				)
				(justify mirror)
			)
		)
		(property "Manufacturer" "Diodes Incorporated"
			(at 0 0 270)
			(unlocked yes)
			(layer "B.Fab")
			(hide yes)
			(effects
				(font
					(size 1 1)
					(thickness 0.15)
				)
				(justify mirror)
			)
		)
		(property "Author" "Antmicro"
			(at 0 0 270)
			(unlocked yes)
			(layer "B.Fab")
			(hide yes)
			(effects
				(font
					(size 1 1)
					(thickness 0.15)
				)
				(justify mirror)
			)
		)
		(property "License" "Apache-2.0"
			(at 0 0 270)
			(unlocked yes)
			(layer "B.Fab")
			(hide yes)
			(effects
				(font
					(size 1 1)
					(thickness 0.15)
				)
				(justify mirror)
			)
		)
		(sheetname "/Peripherals/")
		(sheetfile "peripherals.kicad_sch")
		(attr smd)
		(fp_line
			(start -1 1.5)
			(end -1 1.375)
			(stroke
				(width 0.15)
				(type solid)
			)
			(layer "B.SilkS")
		)
		(fp_line
			(start 1 1.497)
			(end -1 1.5)
			(stroke
				(width 0.15)
				(type solid)
			)
			(layer "B.SilkS")
		)
		(fp_line
			(start 1 1.497)
			(end 1 1.375)
			(stroke
				(width 0.15)
				(type solid)
			)
			(layer "B.SilkS")
		)
		(fp_line
			(start -1 -1.55)
			(end -1 -1.4)
			(stroke
				(width 0.15)
				(type solid)
			)
			(layer "B.SilkS")
		)
		(fp_line
			(start 1 -1.55)
			(end 1 -1.4)
			(stroke
				(width 0.15)
				(type solid)
			)
			(layer "B.SilkS")
		)
		(fp_line
			(start 1 -1.55)
			(end -1 -1.55)
			(stroke
				(width 0.15)
				(type solid)
			)
			(layer "B.SilkS")
		)
		(fp_circle
			(center -1.44 1.5)
			(end -1.39 1.5)
			(stroke
				(width 0.15)
				(type solid)
			)
			(fill yes)
			(layer "B.SilkS")
		)
		(fp_rect
			(start 1.93 1.7)
			(end -1.93 -1.7)
			(stroke
				(width 0.05)
				(type solid)
			)
			(fill no)
			(layer "B.CrtYd")
		)
		(fp_line
			(start -0.45 1.521)
			(end -0.876 1.096)
			(stroke
				(width 0.15)
				(type solid)
			)
			(layer "B.Fab")
		)
		(fp_rect
			(start 0.875 -1.528)
			(end -0.875 1.525)
			(stroke
				(width 0.15)
				(type solid)
			)
			(fill no)
			(layer "B.Fab")
		)
		(fp_text user "Author: Antmicro"
			(at -1.93 -5 90)
			(layer "B.Fab")
			(effects
				(font
					(size 0.7 0.7)
					(thickness 0.15)
				)
				(justify left bottom mirror)
			)
		)
		(fp_text user "License: Apache-2.0"
			(at -1.93 -6.199 90)
			(layer "B.Fab")
			(effects
				(font
					(size 0.7 0.7)
					(thickness 0.15)
				)
				(justify left bottom mirror)
			)
		)
		(fp_text user "${REFERENCE}"
			(at -1.93 -3.8 90)
			(layer "B.Fab")
			(effects
				(font
					(size 0.7 0.7)
					(thickness 0.15)
				)
				(justify left bottom mirror)
			)
		)
		(pad "1" smd rect
			(at -1.301 0.947)
			(size 0.7 1.2)
			(layers "B.Cu" "B.Mask" "B.Paste")
			(net 838 "/Peripherals/I2C_CONN1_3V3")
			(pinfunction "OUT")
			(pintype "power_out")
		)
		(pad "2" smd rect
			(at -1.301 -0.004)
			(size 0.7 1.2)
			(layers "B.Cu" "B.Mask" "B.Paste")
			(net 1 "GND")
			(pinfunction "GND")
			(pintype "power_in")
		)
		(pad "3" smd rect
			(at -1.301 -0.954)
			(size 0.7 1.2)
			(layers "B.Cu" "B.Mask" "B.Paste")
			(net 1121 "unconnected-(U53-FLG-Pad3)")
			(pinfunction "FLG")
			(pintype "output+no_connect")
		)
		(pad "4" smd rect
			(at 1.299 -0.954)
			(size 0.7 1.2)
			(layers "B.Cu" "B.Mask" "B.Paste")
			(net 90 "/Peripherals/I2C_CONN_PEN")
			(pinfunction "EN")
			(pintype "input")
		)
		(pad "5" smd rect
			(at 1.299 -0.004)
			(size 0.7 1.2)
			(layers "B.Cu" "B.Mask" "B.Paste")
			(net 1009 "Net-(U53-ISET)")
			(pinfunction "ISET")
			(pintype "passive")
		)
		(pad "6" smd rect
			(at 1.299 0.947)
			(size 0.7 1.2)
			(layers "B.Cu" "B.Mask" "B.Paste")
			(net 2 "+3V3")
			(pinfunction "IN")
			(pintype "power_in")
		)
	)
)
